# S9S_MB_2U (Grand Teton) — schematic netlist excerpt (pin names and nets, part order shuffled) for the footprints in the layout excerpt that follows; sources: Cadence DE-HDL packaged netlist, KiCad conversion of 03242023_DA0F0TMBIJ0_F0T_Motherboard_J_brd_V01_OCP.brd

R592  Q_RES  2.2K 5% EMPTY  pkg 0402LF  page 241 : A = SMB_FAN_3V3AUX_SCL ; B = P3V3_AUX
R3486  Q_RES  33.2 1% CHIP  pkg 0402LF  page 213 : A = GPU_PRSNT_N_ISO ; B = GPU_PRSNT_N_ISO_R

(kicad_pcb
	(version 20260206)
	(generator "pcbnew")
	(generator_version "10.0")
	(general
		(thickness 1.6)
		(legacy_teardrops no)
	)
	(paper "A4")
	(title_block
		(title "03242023_DA0F0TMBIJ0_F0T_Motherboard_J_brd_V01_OCP.brd")
		(comment 1 "Grand Teton / footprints 6046-6047 of 6105")
	)
	(layers
		(0 "F.Cu" signal "TOP")
		(4 "In1.Cu" signal "GND")
		(6 "In2.Cu" signal "IN1")
		(8 "In3.Cu" signal "GND1")
		(10 "In4.Cu" signal "IN2")
		(12 "In5.Cu" signal "GND2")
		(14 "In6.Cu" signal "IN3")
		(16 "In7.Cu" signal "GND3")
		(18 "In8.Cu" signal "VCC")
		(20 "In9.Cu" signal "VCC1")
		(22 "In10.Cu" signal "GND4")
		(24 "In11.Cu" signal "IN4")
		(26 "In12.Cu" signal "GND5")
		(28 "In13.Cu" signal "IN5")
		(30 "In14.Cu" signal "GND6")
		(32 "In15.Cu" signal "IN6")
		(34 "In16.Cu" signal "GND7")
		(2 "B.Cu" signal "BOTTOM")
		(9 "F.Adhes" user "F.Adhesive")
		(11 "B.Adhes" user "B.Adhesive")
		(13 "F.Paste" user "Package Geometry/Pastemask Top")
		(15 "B.Paste" user "Package Geometry/Pastemask Bottom")
		(5 "F.SilkS" user "Ref Des/Silkscreen Top")
		(7 "B.SilkS" user "Ref Des/Silkscreen Bottom")
		(1 "F.Mask" user "Board Geometry/Soldermask Top")
		(3 "B.Mask" user "Board Geometry/Soldermask Bottom")
		(17 "Dwgs.User" user "User.Drawings")
		(19 "Cmts.User" user "User.Comments")
		(21 "Eco1.User" user "User.Eco1")
		(23 "Eco2.User" user "User.Eco2")
		(25 "Edge.Cuts" user "Board Geometry/Outline")
		(27 "Margin" user)
		(31 "F.CrtYd" user "Package Geometry/Place Bound Top")
		(29 "B.CrtYd" user "Package Geometry/Place Bound Bottom")
		(35 "F.Fab" user "Ref Des/Assembly Top")
		(33 "B.Fab" user "Ref Des/Assembly Bottom")
	)
	(footprint ""
		(layer "B.Cu")
		(at 160.30702 -14.549628 -90)
		(property "Reference" "R592"
			(at 0 0 90)
			(layer "B.SilkS")
			(hide yes)
			(effects
				(font
					(size 1.27 1.27)
				)
				(justify mirror)
			)
		)
		(property "Value" ""
			(at 0 0 90)
			(layer "B.Fab")
			(effects
				(font
					(size 1.27 1.27)
				)
				(justify mirror)
			)
		)
		(duplicate_pad_numbers_are_jumpers no)
		(fp_line
			(start -0.7874 0.4064)
			(end 0.7874 0.4064)
			(stroke
				(width 0.1524)
				(type default)
			)
			(layer "B.SilkS")
		)
		(fp_line
			(start 0.7874 0.4064)
			(end 0.7874 -0.4064)
			(stroke
				(width 0.1524)
				(type default)
			)
			(layer "B.SilkS")
		)
		(fp_line
			(start -0.7874 -0.4064)
			(end -0.7874 0.4064)
			(stroke
				(width 0.1524)
				(type default)
			)
			(layer "B.SilkS")
		)
		(fp_line
			(start 0.7874 -0.4064)
			(end -0.7874 -0.4064)
			(stroke
				(width 0.1524)
				(type default)
			)
			(layer "B.SilkS")
		)
		(fp_line
			(start -0.67945 0.3048)
			(end -0.120396 0.3048)
			(stroke
				(width 0.1)
				(type default)
			)
			(layer "B.Fab")
		)
		(fp_line
			(start -0.120396 0.3048)
			(end -0.120396 0.2794)
			(stroke
				(width 0.1)
				(type default)
			)
			(layer "B.Fab")
		)
		(fp_line
			(start 0.12065 0.3048)
			(end 0.67945 0.3048)
			(stroke
				(width 0.1)
				(type default)
			)
			(layer "B.Fab")
		)
		(fp_line
			(start 0.67945 0.3048)
			(end 0.67945 -0.305054)
			(stroke
				(width 0.1)
				(type default)
			)
			(layer "B.Fab")
		)
		(fp_line
			(start -0.120396 0.2794)
			(end 0.12065 0.2794)
			(stroke
				(width 0.1)
				(type default)
			)
			(layer "B.Fab")
		)
		(fp_line
			(start 0.12065 0.2794)
			(end 0.12065 0.3048)
			(stroke
				(width 0.1)
				(type default)
			)
			(layer "B.Fab")
		)
		(fp_line
			(start -0.12065 -0.2794)
			(end -0.12065 -0.3048)
			(stroke
				(width 0.1)
				(type default)
			)
			(layer "B.Fab")
		)
		(fp_line
			(start 0.12065 -0.2794)
			(end -0.12065 -0.2794)
			(stroke
				(width 0.1)
				(type default)
			)
			(layer "B.Fab")
		)
		(fp_line
			(start -0.67945 -0.3048)
			(end -0.67945 0.3048)
			(stroke
				(width 0.1)
				(type default)
			)
			(layer "B.Fab")
		)
		(fp_line
			(start -0.12065 -0.3048)
			(end -0.67945 -0.3048)
			(stroke
				(width 0.1)
				(type default)
			)
			(layer "B.Fab")
		)
		(fp_line
			(start 0.12065 -0.305054)
			(end 0.12065 -0.2794)
			(stroke
				(width 0.1)
				(type default)
			)
			(layer "B.Fab")
		)
		(fp_line
			(start 0.67945 -0.305054)
			(end 0.12065 -0.305054)
			(stroke
				(width 0.1)
				(type default)
			)
			(layer "B.Fab")
		)
		(pad "1" smd circle
			(at 0.40005 0 90)
			(size 0 0)
			(layers "B.Cu" "B.Mask" "B.Paste")
			(net "SMB_FAN_3V3AUX_SCL")
		)
		(pad "2" smd circle
			(at -0.40005 0 90)
			(size 0 0)
			(layers "B.Cu" "B.Mask" "B.Paste")
			(net "P3V3_AUX")
		)
	)
	(footprint ""
		(layer "B.Cu")
		(at 164.64788 -113.756948 180)
		(property "Reference" "R3486"
			(at 0 0 0)
			(layer "B.SilkS")
			(hide yes)
			(effects
				(font
					(size 1.27 1.27)
				)
				(justify mirror)
			)
		)
		(property "Value" ""
			(at 0 0 0)
			(layer "B.Fab")
			(effects
				(font
					(size 1.27 1.27)
				)
				(justify mirror)
			)
		)
		(duplicate_pad_numbers_are_jumpers no)
		(fp_line
			(start 0.7874 0.4064)
			(end 0.7874 -0.4064)
			(stroke
				(width 0.1524)
				(type default)
			)
			(layer "B.SilkS")
		)
		(fp_line
			(start 0.7874 -0.4064)
			(end -0.7874 -0.4064)
			(stroke
				(width 0.1524)
				(type default)
			)
			(layer "B.SilkS")
		)
		(fp_line
			(start -0.7874 0.4064)
			(end 0.7874 0.4064)
			(stroke
				(width 0.1524)
				(type default)
			)
			(layer "B.SilkS")
		)
		(fp_line
			(start -0.7874 -0.4064)
			(end -0.7874 0.4064)
			(stroke
				(width 0.1524)
				(type default)
			)
			(layer "B.SilkS")
		)
		(fp_line
			(start 0.67945 0.3048)
			(end 0.67945 -0.305054)
			(stroke
				(width 0.1)
				(type default)
			)
			(layer "B.Fab")
		)
		(fp_line
			(start 0.67945 -0.305054)
			(end 0.12065 -0.305054)
			(stroke
				(width 0.1)
				(type default)
			)
			(layer "B.Fab")
		)
		(fp_line
			(start 0.12065 0.3048)
			(end 0.67945 0.3048)
			(stroke
				(width 0.1)
				(type default)
			)
			(layer "B.Fab")
		)
		(fp_line
			(start 0.12065 0.2794)
			(end 0.12065 0.3048)
			(stroke
				(width 0.1)
				(type default)
			)
			(layer "B.Fab")
		)
		(fp_line
			(start 0.12065 -0.2794)
			(end -0.12065 -0.2794)
			(stroke
				(width 0.1)
				(type default)
			)
			(layer "B.Fab")
		)
		(fp_line
			(start 0.12065 -0.305054)
			(end 0.12065 -0.2794)
			(stroke
				(width 0.1)
				(type default)
			)
			(layer "B.Fab")
		)
		(fp_line
			(start -0.120396 0.3048)
			(end -0.120396 0.2794)
			(stroke
				(width 0.1)
				(type default)
			)
			(layer "B.Fab")
		)
		(fp_line
			(start -0.120396 0.2794)
			(end 0.12065 0.2794)
			(stroke
				(width 0.1)
				(type default)
			)
			(layer "B.Fab")
		)
		(fp_line
			(start -0.12065 -0.2794)
			(end -0.12065 -0.3048)
			(stroke
				(width 0.1)
				(type default)
			)
			(layer "B.Fab")
		)
		(fp_line
			(start -0.12065 -0.3048)
			(end -0.67945 -0.3048)
			(stroke
				(width 0.1)
				(type default)
			)
			(layer "B.Fab")
		)
		(fp_line
			(start -0.67945 0.3048)
			(end -0.120396 0.3048)
			(stroke
				(width 0.1)
				(type default)
			)
			(layer "B.Fab")
		)
		(fp_line
			(start -0.67945 -0.3048)
			(end -0.67945 0.3048)
			(stroke
				(width 0.1)
				(type default)
			)
			(layer "B.Fab")
		)
		(pad "1" smd circle
			(at 0.40005 0)
			(size 0 0)
			(layers "B.Cu" "B.Mask" "B.Paste")
			(net "GPU_PRSNT_N_ISO")
		)
		(pad "2" smd circle
			(at -0.40005 0)
			(size 0 0)
			(layers "B.Cu" "B.Mask" "B.Paste")
			(net "GPU_PRSNT_N_ISO_R")
		)
	)
)
